(kicad_pcb
	(version 20260206)
	(generator "pcbnew")
	(generator_version "10.0")
	(general
		(thickness 1.6)
		(legacy_teardrops no)
	)
	(paper "A4")
	(title_block
		(title "01162023_DA0F0TEBIF0_F0T_Expander_BD_F_brd_V02_OCP.brd")
		(comment 1 "Grand Teton / footprint 1840 of 9728 (U6), pads 221-331 of 484")
	)
	(layers
		(0 "F.Cu" signal "TOP")
		(4 "In1.Cu" signal "GND")
		(6 "In2.Cu" signal "VCC")
		(8 "In3.Cu" signal "VCC1")
		(10 "In4.Cu" signal "GND1")
		(12 "In5.Cu" signal "IN1")
		(14 "In6.Cu" signal "GND2")
		(16 "In7.Cu" signal "IN2")
		(18 "In8.Cu" signal "GND3")
		(20 "In9.Cu" signal "IN3")
		(22 "In10.Cu" signal "GND4")
		(24 "In11.Cu" signal "IN4")
		(26 "In12.Cu" signal "GND5")
		(28 "In13.Cu" signal "IN5")
		(30 "In14.Cu" signal "GND6")
		(32 "In15.Cu" signal "IN6")
		(34 "In16.Cu" signal "GND7")
		(2 "B.Cu" signal "BOTTOM")
		(9 "F.Adhes" user "F.Adhesive")
		(11 "B.Adhes" user "B.Adhesive")
		(13 "F.Paste" user "Package Geometry/Pastemask Top")
		(15 "B.Paste" user "Package Geometry/Pastemask Bottom")
		(5 "F.SilkS" user "Ref Des/Silkscreen Top")
		(7 "B.SilkS" user "Ref Des/Silkscreen Bottom")
		(1 "F.Mask" user "Board Geometry/Soldermask Top")
		(3 "B.Mask" user "Board Geometry/Soldermask Bottom")
		(17 "Dwgs.User" user "User.Drawings")
		(19 "Cmts.User" user "User.Comments")
		(21 "Eco1.User" user "User.Eco1")
		(23 "Eco2.User" user "User.Eco2")
		(25 "Edge.Cuts" user "Board Geometry/Outline")
		(27 "Margin" user)
		(31 "F.CrtYd" user "Package Geometry/Place Bound Top")
		(29 "B.CrtYd" user "Package Geometry/Place Bound Bottom")
		(35 "F.Fab" user "Ref Des/Assembly Top")
		(33 "B.Fab" user "Ref Des/Assembly Bottom")
	)
	(footprint ""
		(layer "F.Cu")
		(at 342.493854 -219.587064)
		(property "Reference" "U6"
			(at -10.3632 -10.963148 0)
			(unlocked yes)
			(layer "F.SilkS")
			(effects
				(font
					(size 0.7874 0.5842)
					(thickness 0.1524)
				)
				(justify left)
			)
		)
		(property "Value" ""
			(at 0 0 0)
			(layer "F.Fab")
			(effects
				(font
					(size 1.27 1.27)
				)
			)
		)
		(duplicate_pad_numbers_are_jumpers no)
		(pad "J1" smd circle
			(at -8.400034 -1.999996)
			(size 0.4064 0.4064)
			(layers "F.Cu" "F.Mask" "F.Paste")
			(net "LED_POSTCODE_5")
		)
		(pad "J2" smd circle
			(at -7.599934 -1.999996)
			(size 0.4064 0.4064)
			(layers "F.Cu" "F.Mask" "F.Paste")
			(net "LED_POSTCODE_4")
		)
		(pad "J3" smd circle
			(at -6.800088 -1.999996)
			(size 0.4064 0.4064)
			(layers "F.Cu" "F.Mask" "F.Paste")
			(net "LED_POSTCODE_3")
		)
		(pad "J4" smd circle
			(at -5.999988 -1.999996)
			(size 0.4064 0.4064)
			(layers "F.Cu" "F.Mask" "F.Paste")
			(net "LED_POSTCODE_2")
		)
		(pad "J5" smd circle
			(at -5.199888 -1.999996)
			(size 0.4064 0.4064)
			(layers "F.Cu" "F.Mask" "F.Paste")
			(net "LED_POSTCODE_1")
		)
		(pad "J6" smd circle
			(at -4.400042 -1.999996)
			(size 0.4064 0.4064)
			(layers "F.Cu" "F.Mask" "F.Paste")
			(net "PEX3_SYS_ERR_FPGA")
		)
		(pad "J7" smd circle
			(at -3.599942 -1.999996)
			(size 0.4064 0.4064)
			(layers "F.Cu" "F.Mask" "F.Paste")
			(net "PEX2_SYS_ERR_FPGA")
		)
		(pad "J8" smd circle
			(at -2.800096 -1.999996)
			(size 0.4064 0.4064)
			(layers "F.Cu" "F.Mask" "F.Paste")
			(net "P3V3_FPGA_VCCIO5")
		)
		(pad "J9" smd circle
			(at -1.999996 -1.999996)
			(size 0.4064 0.4064)
			(layers "F.Cu" "F.Mask" "F.Paste")
			(net "GND")
		)
		(pad "J10" smd circle
			(at -1.199896 -1.999996)
			(size 0.4064 0.4064)
			(layers "F.Cu" "F.Mask" "F.Paste")
			(net "GND")
		)
		(pad "J11" smd circle
			(at -0.40005 -1.999996)
			(size 0.4064 0.4064)
			(layers "F.Cu" "F.Mask" "F.Paste")
			(net "GND")
		)
		(pad "J12" smd circle
			(at 0.40005 -1.999996)
			(size 0.4064 0.4064)
			(layers "F.Cu" "F.Mask" "F.Paste")
			(net "GND")
		)
		(pad "J13" smd circle
			(at 1.199896 -1.999996)
			(size 0.4064 0.4064)
			(layers "F.Cu" "F.Mask" "F.Paste")
			(net "GND")
		)
		(pad "J14" smd circle
			(at 1.999996 -1.999996)
			(size 0.4064 0.4064)
			(layers "F.Cu" "F.Mask" "F.Paste")
			(net "GND")
		)
		(pad "J15" smd circle
			(at 2.800096 -1.999996)
			(size 0.4064 0.4064)
			(layers "F.Cu" "F.Mask" "F.Paste")
			(net "P3V3_FPGA_VCCIO1")
		)
		(pad "J16" smd circle
			(at 3.599942 -1.999996)
			(size 0.4064 0.4064)
			(layers "F.Cu" "F.Mask" "F.Paste")
			(net "PWRGD_NIC3_PWR_GOOD_R")
		)
		(pad "J17" smd circle
			(at 4.400042 -1.999996)
			(size 0.4064 0.4064)
			(layers "F.Cu" "F.Mask" "F.Paste")
			(net "NIC3_MAIN_PWR_EN")
		)
		(pad "J18" smd circle
			(at 5.199888 -1.999996)
			(size 0.4064 0.4064)
			(layers "F.Cu" "F.Mask" "F.Paste")
			(net "RST_NIC3_PERST_N")
		)
		(pad "J19" smd circle
			(at 5.999988 -1.999996)
			(size 0.4064 0.4064)
			(layers "F.Cu" "F.Mask" "F.Paste")
			(net "NIC3_CLK_EN_N")
		)
		(pad "J20" smd circle
			(at 6.800088 -1.999996)
			(size 0.4064 0.4064)
			(layers "F.Cu" "F.Mask" "F.Paste")
			(net "PWRGD_P3V3_NIC4_R")
		)
		(pad "J21" smd circle
			(at 7.599934 -1.999996)
			(size 0.4064 0.4064)
			(layers "F.Cu" "F.Mask" "F.Paste")
			(net "PRSNT_NIC4_R_N")
		)
		(pad "J22" smd circle
			(at 8.400034 -1.999996)
			(size 0.4064 0.4064)
			(layers "F.Cu" "F.Mask" "F.Paste")
			(net "PWRGD_P12V_NIC4_R")
		)
		(pad "K1" smd circle
			(at -8.400034 -1.199896)
			(size 0.4064 0.4064)
			(layers "F.Cu" "F.Mask" "F.Paste")
			(net "PRSNT_SSD15_FPGA_N")
		)
		(pad "K2" smd circle
			(at -7.599934 -1.199896)
			(size 0.4064 0.4064)
			(layers "F.Cu" "F.Mask" "F.Paste")
			(net "SMB_BIC_FPGA_R1_SDA")
		)
		(pad "K3" smd circle
			(at -6.800088 -1.199896)
			(size 0.4064 0.4064)
			(layers "F.Cu" "F.Mask" "F.Paste")
			(net "SSD14_PWRDIS_BIC_R")
		)
		(pad "K4" smd circle
			(at -5.999988 -1.199896)
			(size 0.4064 0.4064)
			(layers "F.Cu" "F.Mask" "F.Paste")
			(net "RST_PEX_SSD14_PERST_R_N")
		)
		(pad "K5" smd circle
			(at -5.199888 -1.199896)
			(size 0.4064 0.4064)
			(layers "F.Cu" "F.Mask" "F.Paste")
			(net "SSD14_PEX_PWR_EN_R")
		)
		(pad "K6" smd circle
			(at -4.400042 -1.199896)
			(size 0.4064 0.4064)
			(layers "F.Cu" "F.Mask" "F.Paste")
			(net "LED_POSTCODE_7")
		)
		(pad "K7" smd circle
			(at -3.599942 -1.199896)
			(size 0.4064 0.4064)
			(layers "F.Cu" "F.Mask" "F.Paste")
			(net "LED_POSTCODE_6")
		)
		(pad "K8" smd circle
			(at -2.800096 -1.199896)
			(size 0.4064 0.4064)
			(layers "F.Cu" "F.Mask" "F.Paste")
			(net "P3V3_FPGA_VCCIO5")
		)
		(pad "K9" smd circle
			(at -1.999996 -1.199896)
			(size 0.4064 0.4064)
			(layers "F.Cu" "F.Mask" "F.Paste")
			(net "GND")
		)
		(pad "K10" smd circle
			(at -1.199896 -1.199896)
			(size 0.4064 0.4064)
			(layers "F.Cu" "F.Mask" "F.Paste")
			(net "P3V3_VCC_FPGA_CORE")
		)
		(pad "K11" smd circle
			(at -0.40005 -1.199896)
			(size 0.4064 0.4064)
			(layers "F.Cu" "F.Mask" "F.Paste")
			(net "P3V3_VCC_FPGA_CORE")
		)
		(pad "K12" smd circle
			(at 0.40005 -1.199896)
			(size 0.4064 0.4064)
			(layers "F.Cu" "F.Mask" "F.Paste")
			(net "P3V3_VCC_FPGA_CORE")
		)
		(pad "K13" smd circle
			(at 1.199896 -1.199896)
			(size 0.4064 0.4064)
			(layers "F.Cu" "F.Mask" "F.Paste")
			(net "P3V3_VCC_FPGA_CORE")
		)
		(pad "K14" smd circle
			(at 1.999996 -1.199896)
			(size 0.4064 0.4064)
			(layers "F.Cu" "F.Mask" "F.Paste")
			(net "GND")
		)
		(pad "K15" smd circle
			(at 2.800096 -1.199896)
			(size 0.4064 0.4064)
			(layers "F.Cu" "F.Mask" "F.Paste")
			(net "P3V3_FPGA_VCCIO1")
		)
		(pad "K16" smd circle
			(at 3.599942 -1.199896)
			(size 0.4064 0.4064)
			(layers "F.Cu" "F.Mask" "F.Paste")
			(net "NIC4_CLK_EN_N")
		)
		(pad "K17" smd circle
			(at 4.400042 -1.199896)
			(size 0.4064 0.4064)
			(layers "F.Cu" "F.Mask" "F.Paste")
			(net "RST_NIC4_PERST_N")
		)
		(pad "K18" smd circle
			(at 5.199888 -1.199896)
			(size 0.4064 0.4064)
			(layers "F.Cu" "F.Mask" "F.Paste")
			(net "NIC4_MAIN_PWR_EN")
		)
		(pad "K19" smd circle
			(at 5.999988 -1.199896)
			(size 0.4064 0.4064)
			(layers "F.Cu" "F.Mask" "F.Paste")
			(net "PWRGD_NIC4_PWR_GOOD_R")
		)
		(pad "K20" smd circle
			(at 6.800088 -1.199896)
			(size 0.4064 0.4064)
			(layers "F.Cu" "F.Mask" "F.Paste")
			(net "NIC4_AUX_PWR_EN")
		)
		(pad "K21" smd circle
			(at 7.599934 -1.199896)
			(size 0.4064 0.4064)
			(layers "F.Cu" "F.Mask" "F.Paste")
			(net "GND")
		)
		(pad "K22" smd circle
			(at 8.400034 -1.199896)
			(size 0.4064 0.4064)
			(layers "F.Cu" "F.Mask" "F.Paste")
			(net "PWRGD_NIC5_PWR_GOOD_R")
		)
		(pad "L1" smd circle
			(at -8.400034 -0.40005)
			(size 0.4064 0.4064)
			(layers "F.Cu" "F.Mask" "F.Paste")
			(net "SSD15_PWRDIS_BIC_R")
		)
		(pad "L2" smd circle
			(at -7.599934 -0.40005)
			(size 0.4064 0.4064)
			(layers "F.Cu" "F.Mask" "F.Paste")
			(net "GND")
		)
		(pad "L3" smd circle
			(at -6.800088 -0.40005)
			(size 0.4064 0.4064)
			(layers "F.Cu" "F.Mask" "F.Paste")
			(net "HSC_UV_R_N")
		)
		(pad "L4" smd circle
			(at -5.999988 -0.40005)
			(size 0.4064 0.4064)
			(layers "F.Cu" "F.Mask" "F.Paste")
			(net "HSC_D_OC_FPGA_N")
		)
		(pad "L5" smd circle
			(at -5.199888 -0.40005)
			(size 0.4064 0.4064)
			(layers "F.Cu" "F.Mask" "F.Paste")
			(net "RST_PEX_SSD15_PERST_R_N")
		)
		(pad "L6" smd circle
			(at -4.400042 -0.40005)
			(size 0.4064 0.4064)
			(layers "F.Cu" "F.Mask" "F.Paste")
			(net "SSD15_PEX_PWR_EN_R")
		)
		(pad "L7" smd circle
			(at -3.599942 -0.40005)
			(size 0.4064 0.4064)
			(layers "F.Cu" "F.Mask" "F.Paste")
			(net "PRSNT_SSD14_FPGA_N")
		)
		(pad "L8" smd circle
			(at -2.800096 -0.40005)
			(size 0.4064 0.4064)
			(layers "F.Cu" "F.Mask" "F.Paste")
			(net "P3V3_FPGA_VCCIO4")
		)
		(pad "L9" smd circle
			(at -1.999996 -0.40005)
			(size 0.4064 0.4064)
			(layers "F.Cu" "F.Mask" "F.Paste")
			(net "GND")
		)
		(pad "L10" smd circle
			(at -1.199896 -0.40005)
			(size 0.4064 0.4064)
			(layers "F.Cu" "F.Mask" "F.Paste")
			(net "GND")
		)
		(pad "L11" smd circle
			(at -0.40005 -0.40005)
			(size 0.4064 0.4064)
			(layers "F.Cu" "F.Mask" "F.Paste")
			(net "P3V3_VCC_FPGA_CORE")
		)
		(pad "L12" smd circle
			(at 0.40005 -0.40005)
			(size 0.4064 0.4064)
			(layers "F.Cu" "F.Mask" "F.Paste")
			(net "P3V3_VCC_FPGA_CORE")
		)
		(pad "L13" smd circle
			(at 1.199896 -0.40005)
			(size 0.4064 0.4064)
			(layers "F.Cu" "F.Mask" "F.Paste")
			(net "GND")
		)
		(pad "L14" smd circle
			(at 1.999996 -0.40005)
			(size 0.4064 0.4064)
			(layers "F.Cu" "F.Mask" "F.Paste")
			(net "GND")
		)
		(pad "L15" smd circle
			(at 2.800096 -0.40005)
			(size 0.4064 0.4064)
			(layers "F.Cu" "F.Mask" "F.Paste")
			(net "P3V3_FPGA_VCCIO1")
		)
		(pad "L16" smd circle
			(at 3.599942 -0.40005)
			(size 0.4064 0.4064)
			(layers "F.Cu" "F.Mask" "F.Paste")
			(net "PWRGD_P12V_NIC5_R")
		)
		(pad "L17" smd circle
			(at 4.400042 -0.40005)
			(size 0.4064 0.4064)
			(layers "F.Cu" "F.Mask" "F.Paste")
			(net "PRSNT_NIC5_R_N")
		)
		(pad "L18" smd circle
			(at 5.199888 -0.40005)
			(size 0.4064 0.4064)
			(layers "F.Cu" "F.Mask" "F.Paste")
			(net "GND")
		)
		(pad "L19" smd circle
			(at 5.999988 -0.40005)
			(size 0.4064 0.4064)
			(layers "F.Cu" "F.Mask" "F.Paste")
			(net "PWRGD_P3V3_NIC5_R")
		)
		(pad "L20" smd circle
			(at 6.800088 -0.40005)
			(size 0.4064 0.4064)
			(layers "F.Cu" "F.Mask" "F.Paste")
			(net "NIC5_AUX_PWR_EN")
		)
		(pad "L21" smd circle
			(at 7.599934 -0.40005)
			(size 0.4064 0.4064)
			(layers "F.Cu" "F.Mask" "F.Paste")
			(net "NIC5_MAIN_PWR_EN")
		)
		(pad "L22" smd circle
			(at 8.400034 -0.40005)
			(size 0.4064 0.4064)
			(layers "F.Cu" "F.Mask" "F.Paste")
			(net "RST_NIC5_PERST_N")
		)
		(pad "M1" smd circle
			(at -8.400034 0.40005)
			(size 0.4064 0.4064)
			(layers "F.Cu" "F.Mask" "F.Paste")
			(net "PRSNT_NIC6_FPGA_N")
		)
		(pad "M2" smd circle
			(at -7.599934 0.40005)
			(size 0.4064 0.4064)
			(layers "F.Cu" "F.Mask" "F.Paste")
			(net "SMB_BIC_FPGA_R1_SCL")
		)
		(pad "M3" smd circle
			(at -6.800088 0.40005)
			(size 0.4064 0.4064)
			(layers "F.Cu" "F.Mask" "F.Paste")
			(net "P3V3_FPGA_VCCIO4")
		)
		(pad "M4" smd circle
			(at -5.999988 0.40005)
			(size 0.4064 0.4064)
			(layers "F.Cu" "F.Mask" "F.Paste")
			(net "GND")
		)
		(pad "M5" smd circle
			(at -5.199888 0.40005)
			(size 0.4064 0.4064)
			(layers "F.Cu" "F.Mask" "F.Paste")
			(net "NIC6_MAIN_PWR_BIC_EN_R")
		)
		(pad "M6" smd circle
			(at -4.400042 0.40005)
			(size 0.4064 0.4064)
			(layers "F.Cu" "F.Mask" "F.Paste")
			(net "RST_PEX_NIC6_PERST_R_N")
		)
		(pad "M7" smd circle
			(at -3.599942 0.40005)
			(size 0.4064 0.4064)
			(layers "F.Cu" "F.Mask" "F.Paste")
			(net "SMB_ALERT_HSC_R_N")
		)
		(pad "M8" smd circle
			(at -2.800096 0.40005)
			(size 0.4064 0.4064)
			(layers "F.Cu" "F.Mask" "F.Paste")
			(net "P3V3_FPGA_VCCIO4")
		)
		(pad "M9" smd circle
			(at -1.999996 0.40005)
			(size 0.4064 0.4064)
			(layers "F.Cu" "F.Mask" "F.Paste")
			(net "GND")
		)
		(pad "M10" smd circle
			(at -1.199896 0.40005)
			(size 0.4064 0.4064)
			(layers "F.Cu" "F.Mask" "F.Paste")
			(net "GND")
		)
		(pad "M11" smd circle
			(at -0.40005 0.40005)
			(size 0.4064 0.4064)
			(layers "F.Cu" "F.Mask" "F.Paste")
			(net "P3V3_VCC_FPGA_CORE")
		)
		(pad "M12" smd circle
			(at 0.40005 0.40005)
			(size 0.4064 0.4064)
			(layers "F.Cu" "F.Mask" "F.Paste")
			(net "P3V3_VCC_FPGA_CORE")
		)
		(pad "M13" smd circle
			(at 1.199896 0.40005)
			(size 0.4064 0.4064)
			(layers "F.Cu" "F.Mask" "F.Paste")
			(net "GND")
		)
		(pad "M14" smd circle
			(at 1.999996 0.40005)
			(size 0.4064 0.4064)
			(layers "F.Cu" "F.Mask" "F.Paste")
			(net "GND")
		)
		(pad "M15" smd circle
			(at 2.800096 0.40005)
			(size 0.4064 0.4064)
			(layers "F.Cu" "F.Mask" "F.Paste")
			(net "P3V3_FPGA_VCCIO1")
		)
		(pad "M16" smd circle
			(at 3.599942 0.40005)
			(size 0.4064 0.4064)
			(layers "F.Cu" "F.Mask" "F.Paste")
			(net "PWRGD_NIC6_PWR_GOOD_R")
		)
		(pad "M17" smd circle
			(at 4.400042 0.40005)
			(size 0.4064 0.4064)
			(layers "F.Cu" "F.Mask" "F.Paste")
			(net "NIC5_CLK_EN_N")
		)
		(pad "M18" smd circle
			(at 5.199888 0.40005)
			(size 0.4064 0.4064)
			(layers "F.Cu" "F.Mask" "F.Paste")
			(net "P3V3_FPGA_VCCIO1")
		)
		(pad "M19" smd circle
			(at 5.999988 0.40005)
			(size 0.4064 0.4064)
			(layers "F.Cu" "F.Mask" "F.Paste")
			(net "NIC6_AUX_PWR_EN")
		)
		(pad "M20" smd circle
			(at 6.800088 0.40005)
			(size 0.4064 0.4064)
			(layers "F.Cu" "F.Mask" "F.Paste")
			(net "PWRGD_P3V3_NIC6_R")
		)
		(pad "M21" smd circle
			(at 7.599934 0.40005)
			(size 0.4064 0.4064)
			(layers "F.Cu" "F.Mask" "F.Paste")
			(net "PWRGD_P12V_NIC6_R")
		)
		(pad "M22" smd circle
			(at 8.400034 0.40005)
			(size 0.4064 0.4064)
			(layers "F.Cu" "F.Mask" "F.Paste")
			(net "PRSNT_NIC6_R_N")
		)
		(pad "N1" smd circle
			(at -8.400034 1.199896)
			(size 0.4064 0.4064)
			(layers "F.Cu" "F.Mask" "F.Paste")
			(net "NIC6_PEX_PWR_EN_R")
		)
		(pad "N2" smd circle
			(at -7.599934 1.199896)
			(size 0.4064 0.4064)
			(layers "F.Cu" "F.Mask" "F.Paste")
			(net "Net_1184")
		)
		(pad "N3" smd circle
			(at -6.800088 1.199896)
			(size 0.4064 0.4064)
			(layers "F.Cu" "F.Mask" "F.Paste")
			(net "NIC7_PEX_PWR_EN_R")
		)
		(pad "N4" smd circle
			(at -5.999988 1.199896)
			(size 0.4064 0.4064)
			(layers "F.Cu" "F.Mask" "F.Paste")
			(net "RST_PEX_NIC7_PERST_R_N")
		)
		(pad "N5" smd circle
			(at -5.199888 1.199896)
			(size 0.4064 0.4064)
			(layers "F.Cu" "F.Mask" "F.Paste")
			(net "SSD10_PWRDIS_BIC_R")
		)
		(pad "N6" smd circle
			(at -4.400042 1.199896)
			(size 0.4064 0.4064)
			(layers "F.Cu" "F.Mask" "F.Paste")
			(net "RST_PEX_SSD10_PERST_R_N")
		)
		(pad "N7" smd circle
			(at -3.599942 1.199896)
			(size 0.4064 0.4064)
			(layers "F.Cu" "F.Mask" "F.Paste")
			(net "SSD10_PEX_PWR_EN_R")
		)
		(pad "N8" smd circle
			(at -2.800096 1.199896)
			(size 0.4064 0.4064)
			(layers "F.Cu" "F.Mask" "F.Paste")
			(net "P3V3_FPGA_VCCIO3")
		)
		(pad "N9" smd circle
			(at -1.999996 1.199896)
			(size 0.4064 0.4064)
			(layers "F.Cu" "F.Mask" "F.Paste")
			(net "GND")
		)
		(pad "N10" smd circle
			(at -1.199896 1.199896)
			(size 0.4064 0.4064)
			(layers "F.Cu" "F.Mask" "F.Paste")
			(net "P3V3_VCC_FPGA_CORE")
		)
		(pad "N11" smd circle
			(at -0.40005 1.199896)
			(size 0.4064 0.4064)
			(layers "F.Cu" "F.Mask" "F.Paste")
			(net "P3V3_VCC_FPGA_CORE")
		)
		(pad "N12" smd circle
			(at 0.40005 1.199896)
			(size 0.4064 0.4064)
			(layers "F.Cu" "F.Mask" "F.Paste")
			(net "P3V3_VCC_FPGA_CORE")
		)
		(pad "N13" smd circle
			(at 1.199896 1.199896)
			(size 0.4064 0.4064)
			(layers "F.Cu" "F.Mask" "F.Paste")
			(net "P3V3_VCC_FPGA_CORE")
		)
		(pad "N14" smd circle
			(at 1.999996 1.199896)
			(size 0.4064 0.4064)
			(layers "F.Cu" "F.Mask" "F.Paste")
			(net "GND")
		)
		(pad "N15" smd circle
			(at 2.800096 1.199896)
			(size 0.4064 0.4064)
			(layers "F.Cu" "F.Mask" "F.Paste")
			(net "P3V3_FPGA_VCCIO1")
		)
		(pad "N16" smd circle
			(at 3.599942 1.199896)
			(size 0.4064 0.4064)
			(layers "F.Cu" "F.Mask" "F.Paste")
			(net "NIC6_MAIN_PWR_EN")
		)
		(pad "N17" smd circle
			(at 4.400042 1.199896)
			(size 0.4064 0.4064)
			(layers "F.Cu" "F.Mask" "F.Paste")
			(net "RST_NIC6_PERST_N")
		)
		(pad "N18" smd circle
			(at 5.199888 1.199896)
			(size 0.4064 0.4064)
			(layers "F.Cu" "F.Mask" "F.Paste")
			(net "NIC6_CLK_EN_N")
		)
		(pad "N19" smd circle
			(at 5.999988 1.199896)
			(size 0.4064 0.4064)
			(layers "F.Cu" "F.Mask" "F.Paste")
			(net "NIC7_AUX_PWR_EN")
		)
		(pad "N20" smd circle
			(at 6.800088 1.199896)
			(size 0.4064 0.4064)
			(layers "F.Cu" "F.Mask" "F.Paste")
			(net "PWRGD_P3V3_NIC7_R")
		)
		(pad "N21" smd circle
			(at 7.599934 1.199896)
			(size 0.4064 0.4064)
			(layers "F.Cu" "F.Mask" "F.Paste")
			(net "GND")
		)
		(pad "N22" smd circle
			(at 8.400034 1.199896)
			(size 0.4064 0.4064)
			(layers "F.Cu" "F.Mask" "F.Paste")
			(net "PRSNT_NIC7_R_N")
		)
		(pad "P1" smd circle
			(at -8.400034 1.999996)
			(size 0.4064 0.4064)
			(layers "F.Cu" "F.Mask" "F.Paste")
			(net "PRSNT_NIC7_FPGA_N")
		)
	)
)
